(kicad_pcb
	(version 20260206)
	(generator "pcbnew")
	(generator_version "10.0")
	(general
		(thickness 1.6)
		(legacy_teardrops no)
	)
	(paper "A4")
	(title_block
		(title "fcb — 12433-1M.1206WZS1330.brd")
		(comment 1 "Open Vault / Knox (Wiwynn) / footprints 129-131 of 495")
	)
	(layers
		(0 "F.Cu" signal "TOP")
		(4 "In1.Cu" signal "L2GND")
		(6 "In2.Cu" signal "L3VCC")
		(2 "B.Cu" signal "BOTTOM")
		(9 "F.Adhes" user "F.Adhesive")
		(11 "B.Adhes" user "B.Adhesive")
		(13 "F.Paste" user "Package Geometry/Pastemask Top")
		(15 "B.Paste" user "Package Geometry/Pastemask Bottom")
		(5 "F.SilkS" user "Ref Des/Silkscreen Top")
		(7 "B.SilkS" user "Ref Des/Silkscreen Bottom")
		(1 "F.Mask" user "Board Geometry/Soldermask Top")
		(3 "B.Mask" user "Board Geometry/Soldermask Bottom")
		(17 "Dwgs.User" user "User.Drawings")
		(19 "Cmts.User" user "User.Comments")
		(21 "Eco1.User" user "User.Eco1")
		(23 "Eco2.User" user "User.Eco2")
		(25 "Edge.Cuts" user "Board Geometry/Outline")
		(27 "Margin" user)
		(31 "F.CrtYd" user "Package Geometry/Place Bound Top")
		(29 "B.CrtYd" user "Package Geometry/Place Bound Bottom")
		(35 "F.Fab" user "Ref Des/Assembly Top")
		(33 "B.Fab" user "Ref Des/Assembly Bottom")
	)
	(footprint ""
		(layer "F.Cu")
		(at 21.6916 -140.4366 180)
		(property "Reference" "PU6"
			(at 0 0 180)
			(layer "F.SilkS")
			(hide yes)
			(effects
				(font
					(size 1.27 1.27)
				)
			)
		)
		(property "Value" "TPS2490DGSR-GP"
			(at 0 -11.1252 180)
			(unlocked yes)
			(layer "F.Fab")
			(hide yes)
			(effects
				(font
					(size 1.016 1.016)
					(thickness 0.1524)
				)
			)
		)
		(property "Device Type" "MSOP10H44"
			(at 0 -12.6492 180)
			(unlocked yes)
			(layer "F.Fab")
			(hide yes)
			(effects
				(font
					(size 1.016 1.016)
					(thickness 0.1524)
				)
			)
		)
		(duplicate_pad_numbers_are_jumpers no)
		(fp_line
			(start 1.143 1.016)
			(end -2.0066 1.016)
			(stroke
				(width 0.1524)
				(type default)
			)
			(layer "F.SilkS")
		)
		(fp_line
			(start 1.143 -1.016)
			(end 1.143 1.016)
			(stroke
				(width 0.1524)
				(type default)
			)
			(layer "F.SilkS")
		)
		(fp_line
			(start -1.5748 0)
			(end -1.9558 0.381)
			(stroke
				(width 0.1524)
				(type default)
			)
			(layer "F.SilkS")
		)
		(fp_line
			(start -1.5748 0)
			(end -1.9558 -0.381)
			(stroke
				(width 0.1524)
				(type default)
			)
			(layer "F.SilkS")
		)
		(fp_line
			(start -1.8288 1.016)
			(end -1.8288 3.048)
			(stroke
				(width 0.508)
				(type default)
			)
			(layer "F.SilkS")
		)
		(fp_line
			(start -2.0066 1.016)
			(end -2.0066 -1.016)
			(stroke
				(width 0.1524)
				(type default)
			)
			(layer "F.SilkS")
		)
		(fp_line
			(start -2.0066 -1.016)
			(end 1.143 -1.016)
			(stroke
				(width 0.1524)
				(type default)
			)
			(layer "F.SilkS")
		)
		(fp_poly
			(pts
				(xy -2.0828 3.3401) (xy 2.0828 3.3401) (xy 2.0828 -3.3401) (xy -2.0828 -3.3401)
			)
			(stroke
				(width 0)
				(type default)
			)
			(fill no)
			(layer "F.CrtYd")
		)
		(fp_poly
			(pts
				(xy -2.0828 3.3401) (xy 2.0828 3.3401) (xy 2.0828 -3.3401) (xy -2.0828 -3.3401)
			)
			(stroke
				(width 0)
				(type default)
			)
			(fill no)
			(layer "F.Fab")
		)
		(pad "1" smd rect
			(at -0.99949 2.0701 180)
			(size 0.3048 1.524)
			(layers "F.Cu" "F.Mask" "F.Paste")
			(net "P12VU_2490_EN_2")
		)
		(pad "2" smd rect
			(at -0.50038 2.0701 180)
			(size 0.3048 1.524)
			(layers "F.Cu" "F.Mask" "F.Paste")
			(net "P12VU_2490_VREF")
		)
		(pad "3" smd rect
			(at 0 2.0701 180)
			(size 0.3048 1.524)
			(layers "F.Cu" "F.Mask" "F.Paste")
			(net "P12VU_2490_PROG")
		)
		(pad "4" smd rect
			(at 0.50038 2.0701 180)
			(size 0.3048 1.524)
			(layers "F.Cu" "F.Mask" "F.Paste")
			(net "P12VU_2490_TIMER")
		)
		(pad "5" smd rect
			(at 0.99949 2.0701 180)
			(size 0.3048 1.524)
			(layers "F.Cu" "F.Mask" "F.Paste")
			(net "GND")
		)
		(pad "6" smd rect
			(at 0.99949 -2.0701 180)
			(size 0.3048 1.524)
			(layers "F.Cu" "F.Mask" "F.Paste")
			(net "P12VU_2490_PG")
		)
		(pad "7" smd rect
			(at 0.50038 -2.0701 180)
			(size 0.3048 1.524)
			(layers "F.Cu" "F.Mask" "F.Paste")
			(net "P12VU")
		)
		(pad "8" smd rect
			(at 0 -2.0701 180)
			(size 0.3048 1.524)
			(layers "F.Cu" "F.Mask" "F.Paste")
			(net "P12VU_2490_GATE")
		)
		(pad "9" smd rect
			(at -0.50038 -2.0701 180)
			(size 0.3048 1.524)
			(layers "F.Cu" "F.Mask" "F.Paste")
			(net "P12VU_2490_SENSE")
		)
		(pad "10" smd rect
			(at -0.99949 -2.0701 180)
			(size 0.3048 1.524)
			(layers "F.Cu" "F.Mask" "F.Paste")
			(net "P12VU_2490_VCC")
		)
	)
	(footprint ""
		(layer "F.Cu")
		(at 8.763 -69.1642 90)
		(property "Reference" "R166"
			(at 0 0 90)
			(layer "F.SilkS")
			(hide yes)
			(effects
				(font
					(size 1.27 1.27)
				)
			)
		)
		(property "Value" "4K7R2F-GP"
			(at 0.064008 -3.993896 90)
			(unlocked yes)
			(layer "F.Fab")
			(hide yes)
			(effects
				(font
					(size 1.016 1.016)
					(thickness 0.1524)
				)
			)
		)
		(property "Device Type" "R402H16"
			(at 0.064008 -5.517896 90)
			(unlocked yes)
			(layer "F.Fab")
			(hide yes)
			(effects
				(font
					(size 1.016 1.016)
					(thickness 0.1524)
				)
			)
		)
		(duplicate_pad_numbers_are_jumpers no)
		(fp_line
			(start 0.508 -0.9398)
			(end -0.508 -0.9398)
			(stroke
				(width 0.1524)
				(type default)
			)
			(layer "F.SilkS")
		)
		(fp_line
			(start -0.508 -0.9398)
			(end -0.508 0.9398)
			(stroke
				(width 0.1524)
				(type default)
			)
			(layer "F.SilkS")
		)
		(fp_rect
			(start -0.508 0.9398)
			(end 0.508 -0.9398)
			(stroke
				(width 0)
				(type default)
			)
			(fill no)
			(layer "F.CrtYd")
		)
		(fp_rect
			(start -0.508 0.9398)
			(end 0.508 -0.9398)
			(stroke
				(width 0)
				(type default)
			)
			(fill no)
			(layer "F.Fab")
		)
		(pad "1" smd custom
			(at 0 -0.4445 90)
			(size 0.1397 0.1397)
			(layers "F.Cu" "F.Mask" "F.Paste")
			(net "P3V3")
			(options
				(clearance outline)
				(anchor circle)
			)
			(primitives
				(gr_poly
					(pts
						(arc
							(start -0.1778 -0.2794)
							(mid -0.249642 -0.249642)
							(end -0.2794 -0.1778)
						)
						(arc
							(start -0.2794 0.1778)
							(mid -0.249642 0.249642)
							(end -0.1778 0.2794)
						)
						(arc
							(start 0.1778 0.2794)
							(mid 0.249642 0.249642)
							(end 0.2794 0.1778)
						)
						(arc
							(start 0.2794 -0.1778)
							(mid 0.249642 -0.249642)
							(end 0.1778 -0.2794)
						)
					)
					(width 0)
					(fill yes)
				)
			)
		)
		(pad "2" smd custom
			(at 0 0.4445 90)
			(size 0.1397 0.1397)
			(layers "F.Cu" "F.Mask" "F.Paste")
			(net "PWM_BUFFER_IN_FAN3_FAN4")
			(options
				(clearance outline)
				(anchor circle)
			)
			(primitives
				(gr_poly
					(pts
						(arc
							(start -0.1778 -0.2794)
							(mid -0.249642 -0.249642)
							(end -0.2794 -0.1778)
						)
						(arc
							(start -0.2794 0.1778)
							(mid -0.249642 0.249642)
							(end -0.1778 0.2794)
						)
						(arc
							(start 0.1778 0.2794)
							(mid 0.249642 0.249642)
							(end 0.2794 0.1778)
						)
						(arc
							(start 0.2794 -0.1778)
							(mid 0.249642 -0.249642)
							(end 0.1778 -0.2794)
						)
					)
					(width 0)
					(fill yes)
				)
			)
		)
	)
	(footprint ""
		(layer "F.Cu")
		(at 6.999986 -459.999842)
		(property "Reference" "H5"
			(at 0 0 0)
			(layer "F.SilkS")
			(hide yes)
			(effects
				(font
					(size 1.27 1.27)
				)
			)
		)
		(property "Value" "HOLE315R138"
			(at 0 -7.0612 0)
			(unlocked yes)
			(layer "F.Fab")
			(hide yes)
			(effects
				(font
					(size 1.016 1.016)
					(thickness 0.1524)
				)
			)
		)
		(property "Device Type" "HOLE315R138"
			(at 0 -8.5852 0)
			(unlocked yes)
			(layer "F.Fab")
			(hide yes)
			(effects
				(font
					(size 1.016 1.016)
					(thickness 0.1524)
				)
			)
		)
		(duplicate_pad_numbers_are_jumpers no)
		(fp_poly
			(pts
				(xy 0 4.3053) (xy -0.13462 4.30276) (xy -0.27051 4.29641) (xy -0.40513 4.28625) (xy -0.53975 4.27101)
				(xy -0.6731 4.25196) (xy -0.80645 4.2291) (xy -0.9398 4.20116) (xy -1.07061 4.17068) (xy -1.20142 4.13385)
				(xy -1.33096 4.09448) (xy -1.45796 4.0513) (xy -1.58496 4.00304) (xy -1.70942 3.95097) (xy -1.83261 3.89509)
				(xy -1.95453 3.83667) (xy -2.07391 3.77317) (xy -2.19202 3.70586) (xy -2.30632 3.63474) (xy -2.41935 3.56108)
				(xy -2.53111 3.48361) (xy -2.63906 3.40233) (xy -2.74447 3.31724) (xy -2.84734 3.22961) (xy -2.94767 3.13817)
				(xy -3.04419 3.04419) (xy -3.13817 2.94767) (xy -3.22961 2.84734) (xy -3.31724 2.74447) (xy -3.40233 2.63906)
				(xy -3.48361 2.53111) (xy -3.56108 2.41935) (xy -3.63474 2.30632) (xy -3.70586 2.19202) (xy -3.77317 2.07391)
				(xy -3.83667 1.95453) (xy -3.89509 1.83261) (xy -3.95097 1.70942) (xy -4.00304 1.58496) (xy -4.0513 1.45796)
				(xy -4.09448 1.33096) (xy -4.13385 1.20142) (xy -4.17068 1.07061) (xy -4.20116 0.9398) (xy -4.2291 0.80645)
				(xy -4.25196 0.6731) (xy -4.27101 0.53975) (xy -4.28625 0.40513) (xy -4.29641 0.27051) (xy -4.30276 0.13462)
				(xy -4.3053 0) (xy -4.30276 -0.13462) (xy -4.29641 -0.27051) (xy -4.28625 -0.40513) (xy -4.27101 -0.53975)
				(xy -4.25196 -0.6731) (xy -4.2291 -0.80645) (xy -4.20116 -0.9398) (xy -4.17068 -1.07061) (xy -4.13385 -1.20142)
				(xy -4.09448 -1.33096) (xy -4.0513 -1.45796) (xy -4.00304 -1.58496) (xy -3.95097 -1.70942) (xy -3.89509 -1.83261)
				(xy -3.83667 -1.95453) (xy -3.77317 -2.07391) (xy -3.70586 -2.19202) (xy -3.63474 -2.30632) (xy -3.56108 -2.41935)
				(xy -3.48361 -2.53111) (xy -3.40233 -2.63906) (xy -3.31724 -2.74447) (xy -3.22961 -2.84734) (xy -3.13817 -2.94767)
				(xy -3.04419 -3.04419) (xy -2.94767 -3.13817) (xy -2.84734 -3.22961) (xy -2.74447 -3.31724) (xy -2.63906 -3.40233)
				(xy -2.53111 -3.48361) (xy -2.41935 -3.56108) (xy -2.30632 -3.63474) (xy -2.19202 -3.70586) (xy -2.07391 -3.77317)
				(xy -1.95453 -3.83667) (xy -1.83261 -3.89509) (xy -1.70942 -3.95097) (xy -1.58496 -4.00304) (xy -1.45796 -4.0513)
				(xy -1.33096 -4.09448) (xy -1.20142 -4.13385) (xy -1.07061 -4.17068) (xy -0.9398 -4.20116) (xy -0.80645 -4.2291)
				(xy -0.6731 -4.25196) (xy -0.53975 -4.27101) (xy -0.40513 -4.28625) (xy -0.27051 -4.29641) (xy -0.13462 -4.30276)
				(xy 0 -4.3053) (xy 0.13462 -4.30276) (xy 0.27051 -4.29641) (xy 0.40513 -4.28625) (xy 0.53975 -4.27101)
				(xy 0.6731 -4.25196) (xy 0.80645 -4.2291) (xy 0.9398 -4.20116) (xy 1.07061 -4.17068) (xy 1.20142 -4.13385)
				(xy 1.33096 -4.09448) (xy 1.45796 -4.0513) (xy 1.58496 -4.00304) (xy 1.70942 -3.95097) (xy 1.83261 -3.89509)
				(xy 1.95453 -3.83667) (xy 2.07391 -3.77317) (xy 2.19202 -3.70586) (xy 2.30632 -3.63474) (xy 2.41935 -3.56108)
				(xy 2.53111 -3.48361) (xy 2.63906 -3.40233) (xy 2.74447 -3.31724) (xy 2.84734 -3.22961) (xy 2.94767 -3.13817)
				(xy 3.04419 -3.04419) (xy 3.13817 -2.94767) (xy 3.22961 -2.84734) (xy 3.31724 -2.74447) (xy 3.40233 -2.63906)
				(xy 3.48361 -2.53111) (xy 3.56108 -2.41935) (xy 3.63474 -2.30632) (xy 3.70586 -2.19202) (xy 3.77317 -2.07391)
				(xy 3.83667 -1.95453) (xy 3.89509 -1.83261) (xy 3.95097 -1.70942) (xy 4.00304 -1.58496) (xy 4.0513 -1.45796)
				(xy 4.09448 -1.33096) (xy 4.13385 -1.20142) (xy 4.17068 -1.07061) (xy 4.20116 -0.9398) (xy 4.2291 -0.80645)
				(xy 4.25196 -0.6731) (xy 4.27101 -0.53975) (xy 4.28625 -0.40513) (xy 4.29641 -0.27051) (xy 4.30276 -0.13462)
				(xy 4.3053 0) (xy 4.30276 0.13462) (xy 4.29641 0.27051) (xy 4.28625 0.40513) (xy 4.27101 0.53975)
				(xy 4.25196 0.6731) (xy 4.2291 0.80645) (xy 4.20116 0.9398) (xy 4.17068 1.07061) (xy 4.13385 1.20142)
				(xy 4.09448 1.33096) (xy 4.0513 1.45796) (xy 4.00304 1.58496) (xy 3.95097 1.70942) (xy 3.89509 1.83261)
				(xy 3.83667 1.95453) (xy 3.77317 2.07391) (xy 3.70586 2.19202) (xy 3.63474 2.30632) (xy 3.56108 2.41935)
				(xy 3.48361 2.53111) (xy 3.40233 2.63906) (xy 3.31724 2.74447) (xy 3.22961 2.84734) (xy 3.13817 2.94767)
				(xy 3.04419 3.04419) (xy 2.94767 3.13817) (xy 2.84734 3.22961) (xy 2.74447 3.31724) (xy 2.63906 3.40233)
				(xy 2.53111 3.48361) (xy 2.41935 3.56108) (xy 2.30632 3.63474) (xy 2.19202 3.70586) (xy 2.07391 3.77317)
				(xy 1.95453 3.83667) (xy 1.83261 3.89509) (xy 1.70942 3.95097) (xy 1.58496 4.00304) (xy 1.45796 4.0513)
				(xy 1.33096 4.09448) (xy 1.20142 4.13385) (xy 1.07061 4.17068) (xy 0.9398 4.20116) (xy 0.80645 4.2291)
				(xy 0.6731 4.25196) (xy 0.53975 4.27101) (xy 0.40513 4.28625) (xy 0.27051 4.29641) (xy 0.13462 4.30276)
			)
			(stroke
				(width 0)
				(type default)
			)
			(fill no)
			(layer "F.CrtYd")
		)
		(fp_poly
			(pts
				(xy 0 4.3053) (xy -0.13462 4.30276) (xy -0.27051 4.29641) (xy -0.40513 4.28625) (xy -0.53975 4.27101)
				(xy -0.6731 4.25196) (xy -0.80645 4.2291) (xy -0.9398 4.20116) (xy -1.07061 4.17068) (xy -1.20142 4.13385)
				(xy -1.33096 4.09448) (xy -1.45796 4.0513) (xy -1.58496 4.00304) (xy -1.70942 3.95097) (xy -1.83261 3.89509)
				(xy -1.95453 3.83667) (xy -2.07391 3.77317) (xy -2.19202 3.70586) (xy -2.30632 3.63474) (xy -2.41935 3.56108)
				(xy -2.53111 3.48361) (xy -2.63906 3.40233) (xy -2.74447 3.31724) (xy -2.84734 3.22961) (xy -2.94767 3.13817)
				(xy -3.04419 3.04419) (xy -3.13817 2.94767) (xy -3.22961 2.84734) (xy -3.31724 2.74447) (xy -3.40233 2.63906)
				(xy -3.48361 2.53111) (xy -3.56108 2.41935) (xy -3.63474 2.30632) (xy -3.70586 2.19202) (xy -3.77317 2.07391)
				(xy -3.83667 1.95453) (xy -3.89509 1.83261) (xy -3.95097 1.70942) (xy -4.00304 1.58496) (xy -4.0513 1.45796)
				(xy -4.09448 1.33096) (xy -4.13385 1.20142) (xy -4.17068 1.07061) (xy -4.20116 0.9398) (xy -4.2291 0.80645)
				(xy -4.25196 0.6731) (xy -4.27101 0.53975) (xy -4.28625 0.40513) (xy -4.29641 0.27051) (xy -4.30276 0.13462)
				(xy -4.3053 0) (xy -4.30276 -0.13462) (xy -4.29641 -0.27051) (xy -4.28625 -0.40513) (xy -4.27101 -0.53975)
				(xy -4.25196 -0.6731) (xy -4.2291 -0.80645) (xy -4.20116 -0.9398) (xy -4.17068 -1.07061) (xy -4.13385 -1.20142)
				(xy -4.09448 -1.33096) (xy -4.0513 -1.45796) (xy -4.00304 -1.58496) (xy -3.95097 -1.70942) (xy -3.89509 -1.83261)
				(xy -3.83667 -1.95453) (xy -3.77317 -2.07391) (xy -3.70586 -2.19202) (xy -3.63474 -2.30632) (xy -3.56108 -2.41935)
				(xy -3.48361 -2.53111) (xy -3.40233 -2.63906) (xy -3.31724 -2.74447) (xy -3.22961 -2.84734) (xy -3.13817 -2.94767)
				(xy -3.04419 -3.04419) (xy -2.94767 -3.13817) (xy -2.84734 -3.22961) (xy -2.74447 -3.31724) (xy -2.63906 -3.40233)
				(xy -2.53111 -3.48361) (xy -2.41935 -3.56108) (xy -2.30632 -3.63474) (xy -2.19202 -3.70586) (xy -2.07391 -3.77317)
				(xy -1.95453 -3.83667) (xy -1.83261 -3.89509) (xy -1.70942 -3.95097) (xy -1.58496 -4.00304) (xy -1.45796 -4.0513)
				(xy -1.33096 -4.09448) (xy -1.20142 -4.13385) (xy -1.07061 -4.17068) (xy -0.9398 -4.20116) (xy -0.80645 -4.2291)
				(xy -0.6731 -4.25196) (xy -0.53975 -4.27101) (xy -0.40513 -4.28625) (xy -0.27051 -4.29641) (xy -0.13462 -4.30276)
				(xy 0 -4.3053) (xy 0.13462 -4.30276) (xy 0.27051 -4.29641) (xy 0.40513 -4.28625) (xy 0.53975 -4.27101)
				(xy 0.6731 -4.25196) (xy 0.80645 -4.2291) (xy 0.9398 -4.20116) (xy 1.07061 -4.17068) (xy 1.20142 -4.13385)
				(xy 1.33096 -4.09448) (xy 1.45796 -4.0513) (xy 1.58496 -4.00304) (xy 1.70942 -3.95097) (xy 1.83261 -3.89509)
				(xy 1.95453 -3.83667) (xy 2.07391 -3.77317) (xy 2.19202 -3.70586) (xy 2.30632 -3.63474) (xy 2.41935 -3.56108)
				(xy 2.53111 -3.48361) (xy 2.63906 -3.40233) (xy 2.74447 -3.31724) (xy 2.84734 -3.22961) (xy 2.94767 -3.13817)
				(xy 3.04419 -3.04419) (xy 3.13817 -2.94767) (xy 3.22961 -2.84734) (xy 3.31724 -2.74447) (xy 3.40233 -2.63906)
				(xy 3.48361 -2.53111) (xy 3.56108 -2.41935) (xy 3.63474 -2.30632) (xy 3.70586 -2.19202) (xy 3.77317 -2.07391)
				(xy 3.83667 -1.95453) (xy 3.89509 -1.83261) (xy 3.95097 -1.70942) (xy 4.00304 -1.58496) (xy 4.0513 -1.45796)
				(xy 4.09448 -1.33096) (xy 4.13385 -1.20142) (xy 4.17068 -1.07061) (xy 4.20116 -0.9398) (xy 4.2291 -0.80645)
				(xy 4.25196 -0.6731) (xy 4.27101 -0.53975) (xy 4.28625 -0.40513) (xy 4.29641 -0.27051) (xy 4.30276 -0.13462)
				(xy 4.3053 0) (xy 4.30276 0.13462) (xy 4.29641 0.27051) (xy 4.28625 0.40513) (xy 4.27101 0.53975)
				(xy 4.25196 0.6731) (xy 4.2291 0.80645) (xy 4.20116 0.9398) (xy 4.17068 1.07061) (xy 4.13385 1.20142)
				(xy 4.09448 1.33096) (xy 4.0513 1.45796) (xy 4.00304 1.58496) (xy 3.95097 1.70942) (xy 3.89509 1.83261)
				(xy 3.83667 1.95453) (xy 3.77317 2.07391) (xy 3.70586 2.19202) (xy 3.63474 2.30632) (xy 3.56108 2.41935)
				(xy 3.48361 2.53111) (xy 3.40233 2.63906) (xy 3.31724 2.74447) (xy 3.22961 2.84734) (xy 3.13817 2.94767)
				(xy 3.04419 3.04419) (xy 2.94767 3.13817) (xy 2.84734 3.22961) (xy 2.74447 3.31724) (xy 2.63906 3.40233)
				(xy 2.53111 3.48361) (xy 2.41935 3.56108) (xy 2.30632 3.63474) (xy 2.19202 3.70586) (xy 2.07391 3.77317)
				(xy 1.95453 3.83667) (xy 1.83261 3.89509) (xy 1.70942 3.95097) (xy 1.58496 4.00304) (xy 1.45796 4.0513)
				(xy 1.33096 4.09448) (xy 1.20142 4.13385) (xy 1.07061 4.17068) (xy 0.9398 4.20116) (xy 0.80645 4.2291)
				(xy 0.6731 4.25196) (xy 0.53975 4.27101) (xy 0.40513 4.28625) (xy 0.27051 4.29641) (xy 0.13462 4.30276)
			)
			(stroke
				(width 0)
				(type default)
			)
			(fill no)
			(layer "F.Fab")
		)
		(pad "1" thru_hole circle
			(at 0 0)
			(size 8.001 8.001)
			(drill 3.5052)
			(layers "*.Cu" "*.Mask")
			(remove_unused_layers no)
			(net "GND")
			(clearance -1.7399)
			(thermal_gap 0.3048)
			(padstack
				(mode front_inner_back)
				(layer "Inner"
					(shape circle)
					(size 3.9116 3.9116)
					(clearance 0.3048)
				)
				(layer "B.Cu"
					(shape circle)
					(size 8.001 8.001)
					(clearance -1.7399)
				)
			)
		)
	)
)
